(kicad_pcb
	(version 20260206)
	(generator "pcbnew")
	(generator_version "10.0")
	(general
		(thickness 1.6)
		(legacy_teardrops no)
	)
	(paper "A4")
	(title_block
		(title "9054_F0T_PDB_BD_GPU_F_V04_1213_1550_OCP.brd")
		(comment 1 "Grand Teton / footprints 216-219 of 608")
	)
	(layers
		(0 "F.Cu" signal "TOP")
		(4 "In1.Cu" signal "GND")
		(6 "In2.Cu" signal "IN1")
		(8 "In3.Cu" signal "GND1")
		(10 "In4.Cu" signal "VCC")
		(12 "In5.Cu" signal "VCC1")
		(14 "In6.Cu" signal "GND2")
		(16 "In7.Cu" signal "IN2")
		(18 "In8.Cu" signal "GND3")
		(2 "B.Cu" signal "BOTTOM")
		(9 "F.Adhes" user "F.Adhesive")
		(11 "B.Adhes" user "B.Adhesive")
		(13 "F.Paste" user "Package Geometry/Pastemask Top")
		(15 "B.Paste" user "Package Geometry/Pastemask Bottom")
		(5 "F.SilkS" user "Ref Des/Silkscreen Top")
		(7 "B.SilkS" user "Ref Des/Silkscreen Bottom")
		(1 "F.Mask" user "Board Geometry/Soldermask Top")
		(3 "B.Mask" user "Board Geometry/Soldermask Bottom")
		(17 "Dwgs.User" user "User.Drawings")
		(19 "Cmts.User" user "User.Comments")
		(21 "Eco1.User" user "User.Eco1")
		(23 "Eco2.User" user "User.Eco2")
		(25 "Edge.Cuts" user "Board Geometry/Outline")
		(27 "Margin" user)
		(31 "F.CrtYd" user "Package Geometry/Place Bound Top")
		(29 "B.CrtYd" user "Package Geometry/Place Bound Bottom")
		(35 "F.Fab" user "Ref Des/Assembly Top")
		(33 "B.Fab" user "Ref Des/Assembly Bottom")
	)
	(footprint ""
		(layer "F.Cu")
		(at 69.760084 -2.035048 -90)
		(property "Reference" "J9"
			(at -9.368282 -10.503916 0)
			(unlocked yes)
			(layer "F.SilkS")
			(effects
				(font
					(size 0.7874 0.5842)
					(thickness 0.1524)
				)
			)
		)
		(property "Value" ""
			(at 0 0 270)
			(layer "F.Fab")
			(effects
				(font
					(size 1.27 1.27)
				)
			)
		)
		(duplicate_pad_numbers_are_jumpers no)
		(fp_line
			(start -8.530082 13.72489)
			(end -8.530082 3.034284)
			(stroke
				(width 0.1524)
				(type default)
			)
			(layer "F.SilkS")
		)
		(fp_line
			(start 1.501648 13.72489)
			(end -8.530082 13.72489)
			(stroke
				(width 0.1524)
				(type default)
			)
			(layer "F.SilkS")
		)
		(fp_line
			(start -5.530088 10.724896)
			(end 1.720088 10.724896)
			(stroke
				(width 0.1524)
				(type default)
			)
			(layer "F.SilkS")
		)
		(fp_line
			(start 1.720088 10.724896)
			(end 1.720088 -8.80491)
			(stroke
				(width 0.1524)
				(type default)
			)
			(layer "F.SilkS")
		)
		(fp_line
			(start -8.530082 -5.068316)
			(end -8.530082 -11.804904)
			(stroke
				(width 0.1524)
				(type default)
			)
			(layer "F.SilkS")
		)
		(fp_line
			(start -5.530088 -8.80491)
			(end -5.530088 10.724896)
			(stroke
				(width 0.1524)
				(type default)
			)
			(layer "F.SilkS")
		)
		(fp_line
			(start 1.720088 -8.80491)
			(end -5.530088 -8.80491)
			(stroke
				(width 0.1524)
				(type default)
			)
			(layer "F.SilkS")
		)
		(fp_line
			(start -8.530082 -11.804904)
			(end 1.577848 -11.804904)
			(stroke
				(width 0.1524)
				(type default)
			)
			(layer "F.SilkS")
		)
		(fp_poly
			(pts
				(xy 1.273048 0.24638) (xy 0.780288 0) (xy 1.273048 -0.24638)
			)
			(stroke
				(width 0)
				(type default)
			)
			(fill yes)
			(layer "F.SilkS")
		)
		(fp_line
			(start -8.530082 13.72489)
			(end -8.530082 -11.804904)
			(stroke
				(width 0.1524)
				(type default)
			)
			(layer "B.SilkS")
		)
		(fp_line
			(start 4.720082 13.72489)
			(end -8.530082 13.72489)
			(stroke
				(width 0.1524)
				(type default)
			)
			(layer "B.SilkS")
		)
		(fp_line
			(start -8.530082 -11.804904)
			(end 4.720082 -11.804904)
			(stroke
				(width 0.1524)
				(type default)
			)
			(layer "B.SilkS")
		)
		(fp_line
			(start 4.720082 -11.804904)
			(end 4.720082 13.72489)
			(stroke
				(width 0.1524)
				(type default)
			)
			(layer "B.SilkS")
		)
		(fp_line
			(start -8.530082 13.72489)
			(end -8.530082 -11.804904)
			(stroke
				(width 0.1)
				(type default)
			)
			(layer "B.Fab")
		)
		(fp_line
			(start 4.720082 13.72489)
			(end -8.530082 13.72489)
			(stroke
				(width 0.1)
				(type default)
			)
			(layer "B.Fab")
		)
		(fp_line
			(start -8.530082 -11.804904)
			(end 4.720082 -11.804904)
			(stroke
				(width 0.1)
				(type default)
			)
			(layer "B.Fab")
		)
		(fp_line
			(start 4.720082 -11.804904)
			(end 4.720082 13.72489)
			(stroke
				(width 0.1)
				(type default)
			)
			(layer "B.Fab")
		)
		(fp_line
			(start -5.530088 10.724896)
			(end 1.720088 10.724896)
			(stroke
				(width 0.1)
				(type default)
			)
			(layer "F.Fab")
		)
		(fp_line
			(start 1.720088 10.724896)
			(end 1.720088 -8.80491)
			(stroke
				(width 0.1)
				(type default)
			)
			(layer "F.Fab")
		)
		(fp_line
			(start -5.530088 -8.80491)
			(end -5.530088 10.724896)
			(stroke
				(width 0.1)
				(type default)
			)
			(layer "F.Fab")
		)
		(fp_line
			(start 1.720088 -8.80491)
			(end -5.530088 -8.80491)
			(stroke
				(width 0.1)
				(type default)
			)
			(layer "F.Fab")
		)
		(fp_poly
			(pts
				(xy 2.939288 0.508) (xy 2.939288 -0.508) (xy 1.923288 0)
			)
			(stroke
				(width 0)
				(type default)
			)
			(fill yes)
			(layer "F.Fab")
		)
		(fp_text user "PRESS-FIT"
			(at -7.045452 13.245084 0)
			(unlocked yes)
			(layer "F.SilkS")
			(effects
				(font
					(size 1.27 0.9652)
					(thickness 0.1524)
				)
				(justify left)
			)
		)
		(fp_text user "PRESS-FIT"
			(at -5.553202 -6.846316 0)
			(unlocked yes)
			(layer "B.SilkS")
			(effects
				(font
					(size 1.905 1.4224)
					(thickness 0.1524)
				)
				(justify left mirror)
			)
		)
		(fp_text user "PRESS-FIT"
			(at -6.86435 -7.1501 0)
			(unlocked yes)
			(layer "B.Fab")
			(effects
				(font
					(size 1.905 1.4224)
					(thickness 0.1524)
				)
				(justify left mirror)
			)
		)
		(fp_text user "PRESS-FIT"
			(at -6.88975 9.5123 0)
			(unlocked yes)
			(layer "F.Fab")
			(effects
				(font
					(size 1.905 1.4224)
					(thickness 0.1524)
				)
				(justify left)
			)
		)
		(pad "" np_thru_hole circle
			(at -1.905 8.58012 270)
			(size 2.413 2.413)
			(drill 2.413)
			(layers "*.Cu" "*.Mask")
			(clearance 0.381)
			(thermal_gap 0.381)
		)
		(pad "" np_thru_hole circle
			(at -0.55499 -6.65988 270)
			(size 2.413 2.413)
			(drill 2.413)
			(layers "*.Cu" "*.Mask")
			(clearance 0.381)
			(thermal_gap 0.381)
		)
		(pad "P1" thru_hole circle
			(at -0.55499 6.04012 270)
			(size 1.156208 1.156208)
			(drill 0.749808)
			(layers "*.Cu" "*.Mask")
			(remove_unused_layers no)
			(net "P52V_FAN")
			(clearance 0.0508)
			(thermal_gap 0.0508)
		)
		(pad "P2" thru_hole circle
			(at -0.55499 3.50012 270)
			(size 1.156208 1.156208)
			(drill 0.749808)
			(layers "*.Cu" "*.Mask")
			(remove_unused_layers no)
			(net "P52V_FAN")
			(clearance 0.0508)
			(thermal_gap 0.0508)
		)
		(pad "P3" thru_hole circle
			(at -3.25501 3.50012 270)
			(size 1.156208 1.156208)
			(drill 0.749808)
			(layers "*.Cu" "*.Mask")
			(remove_unused_layers no)
			(net "GND")
			(clearance 0.0508)
			(thermal_gap 0.0508)
		)
		(pad "P4" thru_hole circle
			(at -3.25501 6.04012 270)
			(size 1.156208 1.156208)
			(drill 0.749808)
			(layers "*.Cu" "*.Mask")
			(remove_unused_layers no)
			(net "GND")
			(clearance 0.0508)
			(thermal_gap 0.0508)
		)
		(pad "S1" thru_hole rect
			(at 0 0 270)
			(size 1.156208 1.156208)
			(drill 0.749808)
			(layers "*.Cu" "*.Mask")
			(remove_unused_layers no)
			(net "RST_SMB_FAN_1_R_N")
			(clearance 0.0508)
			(thermal_gap 0.0508)
			(padstack
				(mode front_inner_back)
				(layer "Inner"
					(shape circle)
					(size 1.156208 1.156208)
					(clearance 0.0508)
				)
				(layer "B.Cu"
					(shape rect)
					(size 1.156208 1.156208)
					(clearance 0.0508)
				)
			)
		)
		(pad "S2" thru_hole circle
			(at -1.27 -1.27 270)
			(size 1.156208 1.156208)
			(drill 0.749808)
			(layers "*.Cu" "*.Mask")
			(remove_unused_layers no)
			(net "FAN_PWR_EN_1_R")
			(clearance 0.0508)
			(thermal_gap 0.0508)
		)
		(pad "S3" thru_hole circle
			(at 0 -2.54 270)
			(size 1.156208 1.156208)
			(drill 0.749808)
			(layers "*.Cu" "*.Mask")
			(remove_unused_layers no)
			(net "P12V_FAN_LED")
			(clearance 0.0508)
			(thermal_gap 0.0508)
		)
		(pad "S4" thru_hole circle
			(at -1.27 -3.81 270)
			(size 1.156208 1.156208)
			(drill 0.749808)
			(layers "*.Cu" "*.Mask")
			(remove_unused_layers no)
			(net "P3V3_AUX")
			(clearance 0.0508)
			(thermal_gap 0.0508)
		)
		(pad "S5" thru_hole circle
			(at -3.81 -3.81 270)
			(size 1.156208 1.156208)
			(drill 0.749808)
			(layers "*.Cu" "*.Mask")
			(remove_unused_layers no)
			(net "PRSNT_FAN_BP1_R_N")
			(clearance 0.0508)
			(thermal_gap 0.0508)
		)
		(pad "S6" thru_hole circle
			(at -2.54 -2.54 270)
			(size 1.156208 1.156208)
			(drill 0.749808)
			(layers "*.Cu" "*.Mask")
			(remove_unused_layers no)
			(net "GND")
			(clearance 0.0508)
			(thermal_gap 0.0508)
		)
		(pad "S7" thru_hole circle
			(at -3.81 -1.27 270)
			(size 1.156208 1.156208)
			(drill 0.749808)
			(layers "*.Cu" "*.Mask")
			(remove_unused_layers no)
			(net "SMB_PDB_FAN_1_R_SCL")
			(clearance 0.0508)
			(thermal_gap 0.0508)
		)
		(pad "S8" thru_hole circle
			(at -2.54 0 270)
			(size 1.156208 1.156208)
			(drill 0.749808)
			(layers "*.Cu" "*.Mask")
			(remove_unused_layers no)
			(net "SMB_PDB_FAN_1_R_SDA")
			(clearance 0.0508)
			(thermal_gap 0.0508)
		)
		(zone
			(layers "F.Cu" "B.Cu" "In1.Cu" "In2.Cu" "In3.Cu" "In4.Cu" "In5.Cu" "In6.Cu"
				"In7.Cu" "In8.Cu"
			)
			(hatch none 0.5)
			(connect_pads
				(clearance 0)
			)
			(min_thickness 0.25)
			(keepout
				(tracks not_allowed)
				(vias allowed)
				(pads allowed)
				(copperpour not_allowed)
				(footprints allowed)
			)
			(placement
				(enabled no)
				(sheetname "")
			)
			(fill
				(thermal_gap 0.5)
				(thermal_bridge_width 0.5)
				(island_removal_mode 0)
			)
			(polygon
				(pts
					(arc
						(start 62.894464 -3.940048)
						(mid 59.465464 -3.940048)
						(end 62.894464 -3.940048)
					)
				)
			)
		)
		(zone
			(layers "F.Cu" "B.Cu" "In1.Cu" "In2.Cu" "In3.Cu" "In4.Cu" "In5.Cu" "In6.Cu"
				"In7.Cu" "In8.Cu"
			)
			(hatch none 0.5)
			(connect_pads
				(clearance 0)
			)
			(min_thickness 0.25)
			(keepout
				(tracks not_allowed)
				(vias allowed)
				(pads allowed)
				(copperpour not_allowed)
				(footprints allowed)
			)
			(placement
				(enabled no)
				(sheetname "")
			)
			(fill
				(thermal_gap 0.5)
				(thermal_bridge_width 0.5)
				(island_removal_mode 0)
			)
			(polygon
				(pts
					(arc
						(start 78.134718 -2.590038)
						(mid 74.70521 -2.590038)
						(end 78.134718 -2.590038)
					)
				)
			)
		)
		(zone
			(layer "B.Cu")
			(hatch none 0.5)
			(connect_pads
				(clearance 0)
			)
			(min_thickness 0.25)
			(keepout
				(tracks allowed)
				(vias not_allowed)
				(pads allowed)
				(copperpour not_allowed)
				(footprints allowed)
			)
			(placement
				(enabled no)
				(sheetname "")
			)
			(fill
				(thermal_gap 0.5)
				(thermal_bridge_width 0.5)
				(island_removal_mode 0)
			)
			(polygon
				(pts
					(xy 66.901568 -5.931662) (xy 63.07836 -5.931662) (xy 63.07836 -1.948434) (xy 66.901568 -1.948434)
				)
			)
		)
		(zone
			(layer "B.Cu")
			(hatch none 0.5)
			(connect_pads
				(clearance 0)
			)
			(min_thickness 0.25)
			(keepout
				(tracks allowed)
				(vias not_allowed)
				(pads allowed)
				(copperpour not_allowed)
				(footprints allowed)
			)
			(placement
				(enabled no)
				(sheetname "")
			)
			(fill
				(thermal_gap 0.5)
				(thermal_bridge_width 0.5)
				(island_removal_mode 0)
			)
			(polygon
				(pts
					(xy 74.211688 -6.486652) (xy 69.11848 -6.486652) (xy 69.11848 -1.393444) (xy 74.211688 -1.393444)
				)
			)
		)
	)
	(footprint ""
		(layer "F.Cu")
		(at 334.631284 -39.0652 -90)
		(property "Reference" "PR16"
			(at 0 0 270)
			(layer "F.SilkS")
			(hide yes)
			(effects
				(font
					(size 1.27 1.27)
				)
			)
		)
		(property "Value" ""
			(at 0 0 270)
			(layer "F.Fab")
			(effects
				(font
					(size 1.27 1.27)
				)
			)
		)
		(duplicate_pad_numbers_are_jumpers no)
		(fp_line
			(start -1.2954 0.5842)
			(end -1.2954 -0.5842)
			(stroke
				(width 0.1524)
				(type default)
			)
			(layer "F.SilkS")
		)
		(fp_line
			(start 1.2954 0.5842)
			(end -1.2954 0.5842)
			(stroke
				(width 0.1524)
				(type default)
			)
			(layer "F.SilkS")
		)
		(fp_line
			(start -1.2954 -0.5842)
			(end 1.2954 -0.5842)
			(stroke
				(width 0.1524)
				(type default)
			)
			(layer "F.SilkS")
		)
		(fp_line
			(start 1.2954 -0.5842)
			(end 1.2954 0.5842)
			(stroke
				(width 0.1524)
				(type default)
			)
			(layer "F.SilkS")
		)
		(fp_line
			(start -0.8636 0.4572)
			(end -0.8636 0.4318)
			(stroke
				(width 0.1)
				(type default)
			)
			(layer "F.Fab")
		)
		(fp_line
			(start 0.8636 0.4572)
			(end -0.8636 0.4572)
			(stroke
				(width 0.1)
				(type default)
			)
			(layer "F.Fab")
		)
		(fp_line
			(start -0.8636 0.4318)
			(end -0.8636 0.4064)
			(stroke
				(width 0.1)
				(type default)
			)
			(layer "F.Fab")
		)
		(fp_line
			(start -1.1938 0.4064)
			(end -1.1938 -0.406654)
			(stroke
				(width 0.1)
				(type default)
			)
			(layer "F.Fab")
		)
		(fp_line
			(start -0.8636 0.4064)
			(end -1.1938 0.4064)
			(stroke
				(width 0.1)
				(type default)
			)
			(layer "F.Fab")
		)
		(fp_line
			(start 0.8636 0.4064)
			(end 0.8636 0.4572)
			(stroke
				(width 0.1)
				(type default)
			)
			(layer "F.Fab")
		)
		(fp_line
			(start 1.1938 0.4064)
			(end 0.8636 0.4064)
			(stroke
				(width 0.1)
				(type default)
			)
			(layer "F.Fab")
		)
		(fp_line
			(start -1.1938 -0.406654)
			(end -0.8636 -0.406654)
			(stroke
				(width 0.1)
				(type default)
			)
			(layer "F.Fab")
		)
		(fp_line
			(start -0.8636 -0.406654)
			(end -0.8636 -0.4572)
			(stroke
				(width 0.1)
				(type default)
			)
			(layer "F.Fab")
		)
		(fp_line
			(start 0.8636 -0.406654)
			(end 1.1938 -0.406654)
			(stroke
				(width 0.1)
				(type default)
			)
			(layer "F.Fab")
		)
		(fp_line
			(start 1.1938 -0.406654)
			(end 1.1938 0.4064)
			(stroke
				(width 0.1)
				(type default)
			)
			(layer "F.Fab")
		)
		(fp_line
			(start -0.8636 -0.4572)
			(end 0.8636 -0.4572)
			(stroke
				(width 0.1)
				(type default)
			)
			(layer "F.Fab")
		)
		(fp_line
			(start 0.8636 -0.4572)
			(end 0.8636 -0.406654)
			(stroke
				(width 0.1)
				(type default)
			)
			(layer "F.Fab")
		)
		(pad "1" smd rect
			(at -0.7366 0 180)
			(size 0.7112 0.8128)
			(layers "F.Cu" "F.Mask" "F.Paste")
			(net "P52V_HS1_GATE2_R")
		)
		(pad "2" smd rect
			(at 0.7366 0 180)
			(size 0.7112 0.8128)
			(layers "F.Cu" "F.Mask" "F.Paste")
			(net "P52V_HS1_GATE6")
		)
	)
	(footprint ""
		(layer "F.Cu")
		(at 448.437 -38.862)
		(property "Reference" "C2"
			(at 0 0 0)
			(layer "F.SilkS")
			(hide yes)
			(effects
				(font
					(size 1.27 1.27)
				)
			)
		)
		(property "Value" ""
			(at 0 0 0)
			(layer "F.Fab")
			(effects
				(font
					(size 1.27 1.27)
				)
			)
		)
		(duplicate_pad_numbers_are_jumpers no)
		(fp_line
			(start -0.7874 -0.4064)
			(end 0.7874 -0.4064)
			(stroke
				(width 0.1524)
				(type default)
			)
			(layer "F.SilkS")
		)
		(fp_line
			(start -0.7874 0.4064)
			(end -0.7874 -0.4064)
			(stroke
				(width 0.1524)
				(type default)
			)
			(layer "F.SilkS")
		)
		(fp_line
			(start 0.7874 -0.4064)
			(end 0.7874 0.4064)
			(stroke
				(width 0.1524)
				(type default)
			)
			(layer "F.SilkS")
		)
		(fp_line
			(start 0.7874 0.4064)
			(end -0.7874 0.4064)
			(stroke
				(width 0.1524)
				(type default)
			)
			(layer "F.SilkS")
		)
		(fp_line
			(start -0.67945 -0.305054)
			(end -0.12065 -0.305054)
			(stroke
				(width 0.1)
				(type default)
			)
			(layer "F.Fab")
		)
		(fp_line
			(start -0.67945 0.3048)
			(end -0.67945 -0.305054)
			(stroke
				(width 0.1)
				(type default)
			)
			(layer "F.Fab")
		)
		(fp_line
			(start -0.12065 -0.305054)
			(end -0.12065 -0.2794)
			(stroke
				(width 0.1)
				(type default)
			)
			(layer "F.Fab")
		)
		(fp_line
			(start -0.12065 -0.2794)
			(end 0.12065 -0.2794)
			(stroke
				(width 0.1)
				(type default)
			)
			(layer "F.Fab")
		)
		(fp_line
			(start -0.12065 0.2794)
			(end -0.12065 0.3048)
			(stroke
				(width 0.1)
				(type default)
			)
			(layer "F.Fab")
		)
		(fp_line
			(start -0.12065 0.3048)
			(end -0.67945 0.3048)
			(stroke
				(width 0.1)
				(type default)
			)
			(layer "F.Fab")
		)
		(fp_line
			(start 0.120396 0.2794)
			(end -0.12065 0.2794)
			(stroke
				(width 0.1)
				(type default)
			)
			(layer "F.Fab")
		)
		(fp_line
			(start 0.120396 0.3048)
			(end 0.120396 0.2794)
			(stroke
				(width 0.1)
				(type default)
			)
			(layer "F.Fab")
		)
		(fp_line
			(start 0.12065 -0.3048)
			(end 0.67945 -0.3048)
			(stroke
				(width 0.1)
				(type default)
			)
			(layer "F.Fab")
		)
		(fp_line
			(start 0.12065 -0.2794)
			(end 0.12065 -0.3048)
			(stroke
				(width 0.1)
				(type default)
			)
			(layer "F.Fab")
		)
		(fp_line
			(start 0.67945 -0.3048)
			(end 0.67945 0.3048)
			(stroke
				(width 0.1)
				(type default)
			)
			(layer "F.Fab")
		)
		(fp_line
			(start 0.67945 0.3048)
			(end 0.120396 0.3048)
			(stroke
				(width 0.1)
				(type default)
			)
			(layer "F.Fab")
		)
		(pad "1" smd circle
			(at -0.40005 0)
			(size 0 0)
			(layers "F.Cu" "F.Mask" "F.Paste")
			(net "P3V3_AUX")
		)
		(pad "2" smd circle
			(at 0.40005 0)
			(size 0 0)
			(layers "F.Cu" "F.Mask" "F.Paste")
			(net "GND")
		)
	)
	(footprint ""
		(layer "F.Cu")
		(at 430.276 -43.18 180)
		(property "Reference" "R97"
			(at 0 0 180)
			(layer "F.SilkS")
			(hide yes)
			(effects
				(font
					(size 1.27 1.27)
				)
			)
		)
		(property "Value" ""
			(at 0 0 180)
			(layer "F.Fab")
			(effects
				(font
					(size 1.27 1.27)
				)
			)
		)
		(duplicate_pad_numbers_are_jumpers no)
		(fp_line
			(start 0.7874 0.4064)
			(end -0.7874 0.4064)
			(stroke
				(width 0.1524)
				(type default)
			)
			(layer "F.SilkS")
		)
		(fp_line
			(start 0.7874 -0.4064)
			(end 0.7874 0.4064)
			(stroke
				(width 0.1524)
				(type default)
			)
			(layer "F.SilkS")
		)
		(fp_line
			(start -0.7874 0.4064)
			(end -0.7874 -0.4064)
			(stroke
				(width 0.1524)
				(type default)
			)
			(layer "F.SilkS")
		)
		(fp_line
			(start -0.7874 -0.4064)
			(end 0.7874 -0.4064)
			(stroke
				(width 0.1524)
				(type default)
			)
			(layer "F.SilkS")
		)
		(fp_line
			(start 0.67945 0.3048)
			(end 0.120396 0.3048)
			(stroke
				(width 0.1)
				(type default)
			)
			(layer "F.Fab")
		)
		(fp_line
			(start 0.67945 -0.3048)
			(end 0.67945 0.3048)
			(stroke
				(width 0.1)
				(type default)
			)
			(layer "F.Fab")
		)
		(fp_line
			(start 0.12065 -0.2794)
			(end 0.12065 -0.3048)
			(stroke
				(width 0.1)
				(type default)
			)
			(layer "F.Fab")
		)
		(fp_line
			(start 0.12065 -0.3048)
			(end 0.67945 -0.3048)
			(stroke
				(width 0.1)
				(type default)
			)
			(layer "F.Fab")
		)
		(fp_line
			(start 0.120396 0.3048)
			(end 0.120396 0.2794)
			(stroke
				(width 0.1)
				(type default)
			)
			(layer "F.Fab")
		)
		(fp_line
			(start 0.120396 0.2794)
			(end -0.12065 0.2794)
			(stroke
				(width 0.1)
				(type default)
			)
			(layer "F.Fab")
		)
		(fp_line
			(start -0.12065 0.3048)
			(end -0.67945 0.3048)
			(stroke
				(width 0.1)
				(type default)
			)
			(layer "F.Fab")
		)
		(fp_line
			(start -0.12065 0.2794)
			(end -0.12065 0.3048)
			(stroke
				(width 0.1)
				(type default)
			)
			(layer "F.Fab")
		)
		(fp_line
			(start -0.12065 -0.2794)
			(end 0.12065 -0.2794)
			(stroke
				(width 0.1)
				(type default)
			)
			(layer "F.Fab")
		)
		(fp_line
			(start -0.12065 -0.305054)
			(end -0.12065 -0.2794)
			(stroke
				(width 0.1)
				(type default)
			)
			(layer "F.Fab")
		)
		(fp_line
			(start -0.67945 0.3048)
			(end -0.67945 -0.305054)
			(stroke
				(width 0.1)
				(type default)
			)
			(layer "F.Fab")
		)
		(fp_line
			(start -0.67945 -0.305054)
			(end -0.12065 -0.305054)
			(stroke
				(width 0.1)
				(type default)
			)
			(layer "F.Fab")
		)
		(pad "1" smd circle
			(at -0.40005 0 180)
			(size 0 0)
			(layers "F.Cu" "F.Mask" "F.Paste")
			(net "P3V3_AUX")
		)
		(pad "2" smd circle
			(at 0.40005 0 180)
			(size 0 0)
			(layers "F.Cu" "F.Mask" "F.Paste")
			(net "SKU_ID_1")
		)
	)
)
